FILE_TYPE=LIBRARY_PARTS;
primitive 'CONN60_101062636003K02LF';
  pin
    'A2':
      PIN_NUMBER='(A2)';
      BIDIRECTIONAL='TRUE';
      INPUT_LOAD='(-0.01,0.01)';
      OUTPUT_LOAD='(1.0,-1.0)';
    'B2':
      PIN_NUMBER='(B2)';
      BIDIRECTIONAL='TRUE';
      INPUT_LOAD='(-0.01,0.01)';
      OUTPUT_LOAD='(1.0,-1.0)';
    'C2':
      PIN_NUMBER='(C2)';
      BIDIRECTIONAL='TRUE';
      INPUT_LOAD='(-0.01,0.01)';
      OUTPUT_LOAD='(1.0,-1.0)';
    'D2':
      PIN_NUMBER='(D2)';
      BIDIRECTIONAL='TRUE';
      INPUT_LOAD='(-0.01,0.01)';
      OUTPUT_LOAD='(1.0,-1.0)';
    'P1_1':
      PIN_NUMBER='(P1_1)';
      PINUSE='POWER';
      NO_LOAD_CHECK='Both';
      NO_IO_CHECK='Both';
      NO_ASSERT_CHECK='TRUE';
      NO_DIR_CHECK='TRUE';
      ALLOW_CONNECT='TRUE';
    'P1_2':
      PIN_NUMBER='(P1_2)';
      PINUSE='POWER';
      NO_LOAD_CHECK='Both';
      NO_IO_CHECK='Both';
      NO_ASSERT_CHECK='TRUE';
      NO_DIR_CHECK='TRUE';
      ALLOW_CONNECT='TRUE';
    'P1_3':
      PIN_NUMBER='(P1_3)';
      PINUSE='POWER';
      NO_LOAD_CHECK='Both';
      NO_IO_CHECK='Both';
      NO_ASSERT_CHECK='TRUE';
      NO_DIR_CHECK='TRUE';
      ALLOW_CONNECT='TRUE';
    'P1_4':
      PIN_NUMBER='(P1_4)';
      PINUSE='POWER';
      NO_LOAD_CHECK='Both';
      NO_IO_CHECK='Both';
      NO_ASSERT_CHECK='TRUE';
      NO_DIR_CHECK='TRUE';
      ALLOW_CONNECT='TRUE';
    'P1_5':
      PIN_NUMBER='(P1_5)';
      PINUSE='POWER';
      NO_LOAD_CHECK='Both';
      NO_IO_CHECK='Both';
      NO_ASSERT_CHECK='TRUE';
      NO_DIR_CHECK='TRUE';
      ALLOW_CONNECT='TRUE';
    'P1_6':
      PIN_NUMBER='(P1_6)';
      PINUSE='POWER';
      NO_LOAD_CHECK='Both';
      NO_IO_CHECK='Both';
      NO_ASSERT_CHECK='TRUE';
      NO_DIR_CHECK='TRUE';
      ALLOW_CONNECT='TRUE';
    'P1_7':
      PIN_NUMBER='(P1_7)';
      PINUSE='POWER';
      NO_LOAD_CHECK='Both';
      NO_IO_CHECK='Both';
      NO_ASSERT_CHECK='TRUE';
      NO_DIR_CHECK='TRUE';
      ALLOW_CONNECT='TRUE';
    'P1_8':
      PIN_NUMBER='(P1_8)';
      PINUSE='POWER';
      NO_LOAD_CHECK='Both';
      NO_IO_CHECK='Both';
      NO_ASSERT_CHECK='TRUE';
      NO_DIR_CHECK='TRUE';
      ALLOW_CONNECT='TRUE';
    'P2_1':
      PIN_NUMBER='(P2_1)';
      PINUSE='POWER';
      NO_LOAD_CHECK='Both';
      NO_IO_CHECK='Both';
      NO_ASSERT_CHECK='TRUE';
      NO_DIR_CHECK='TRUE';
      ALLOW_CONNECT='TRUE';
    'P2_2':
      PIN_NUMBER='(P2_2)';
      PINUSE='POWER';
      NO_LOAD_CHECK='Both';
      NO_IO_CHECK='Both';
      NO_ASSERT_CHECK='TRUE';
      NO_DIR_CHECK='TRUE';
      ALLOW_CONNECT='TRUE';
    'P2_3':
      PIN_NUMBER='(P2_3)';
      PINUSE='POWER';
      NO_LOAD_CHECK='Both';
      NO_IO_CHECK='Both';
      NO_ASSERT_CHECK='TRUE';
      NO_DIR_CHECK='TRUE';
      ALLOW_CONNECT='TRUE';
    'P2_4':
      PIN_NUMBER='(P2_4)';
      PINUSE='POWER';
      NO_LOAD_CHECK='Both';
      NO_IO_CHECK='Both';
      NO_ASSERT_CHECK='TRUE';
      NO_DIR_CHECK='TRUE';
      ALLOW_CONNECT='TRUE';
    'P2_5':
      PIN_NUMBER='(P2_5)';
      PINUSE='POWER';
      NO_LOAD_CHECK='Both';
      NO_IO_CHECK='Both';
      NO_ASSERT_CHECK='TRUE';
      NO_DIR_CHECK='TRUE';
      ALLOW_CONNECT='TRUE';
    'P2_6':
      PIN_NUMBER='(P2_6)';
      PINUSE='POWER';
      NO_LOAD_CHECK='Both';
      NO_IO_CHECK='Both';
      NO_ASSERT_CHECK='TRUE';
      NO_DIR_CHECK='TRUE';
      ALLOW_CONNECT='TRUE';
    'P2_7':
      PIN_NUMBER='(P2_7)';
      PINUSE='POWER';
      NO_LOAD_CHECK='Both';
      NO_IO_CHECK='Both';
      NO_ASSERT_CHECK='TRUE';
      NO_DIR_CHECK='TRUE';
      ALLOW_CONNECT='TRUE';
    'P2_8':
      PIN_NUMBER='(P2_8)';
      PINUSE='POWER';
      NO_LOAD_CHECK='Both';
      NO_IO_CHECK='Both';
      NO_ASSERT_CHECK='TRUE';
      NO_DIR_CHECK='TRUE';
      ALLOW_CONNECT='TRUE';
    'P4_1':
      PIN_NUMBER='(P4_1)';
      PINUSE='POWER';
      NO_LOAD_CHECK='Both';
      NO_IO_CHECK='Both';
      NO_ASSERT_CHECK='TRUE';
      NO_DIR_CHECK='TRUE';
      ALLOW_CONNECT='TRUE';
    'P4_2':
      PIN_NUMBER='(P4_2)';
      PINUSE='POWER';
      NO_LOAD_CHECK='Both';
      NO_IO_CHECK='Both';
      NO_ASSERT_CHECK='TRUE';
      NO_DIR_CHECK='TRUE';
      ALLOW_CONNECT='TRUE';
    'P4_3':
      PIN_NUMBER='(P4_3)';
      PINUSE='POWER';
      NO_LOAD_CHECK='Both';
      NO_IO_CHECK='Both';
      NO_ASSERT_CHECK='TRUE';
      NO_DIR_CHECK='TRUE';
      ALLOW_CONNECT='TRUE';
    'P4_4':
      PIN_NUMBER='(P4_4)';
      PINUSE='POWER';
      NO_LOAD_CHECK='Both';
      NO_IO_CHECK='Both';
      NO_ASSERT_CHECK='TRUE';
      NO_DIR_CHECK='TRUE';
      ALLOW_CONNECT='TRUE';
    'P4_5':
      PIN_NUMBER='(P4_5)';
      PINUSE='POWER';
      NO_LOAD_CHECK='Both';
      NO_IO_CHECK='Both';
      NO_ASSERT_CHECK='TRUE';
      NO_DIR_CHECK='TRUE';
      ALLOW_CONNECT='TRUE';
    'P4_6':
      PIN_NUMBER='(P4_6)';
      PINUSE='POWER';
      NO_LOAD_CHECK='Both';
      NO_IO_CHECK='Both';
      NO_ASSERT_CHECK='TRUE';
      NO_DIR_CHECK='TRUE';
      ALLOW_CONNECT='TRUE';
    'P4_7':
      PIN_NUMBER='(P4_7)';
      PINUSE='POWER';
      NO_LOAD_CHECK='Both';
      NO_IO_CHECK='Both';
      NO_ASSERT_CHECK='TRUE';
      NO_DIR_CHECK='TRUE';
      ALLOW_CONNECT='TRUE';
    'P4_8':
      PIN_NUMBER='(P4_8)';
      PINUSE='POWER';
      NO_LOAD_CHECK='Both';
      NO_IO_CHECK='Both';
      NO_ASSERT_CHECK='TRUE';
      NO_DIR_CHECK='TRUE';
      ALLOW_CONNECT='TRUE';
    'A1':
      PIN_NUMBER='(A1)';
      BIDIRECTIONAL='TRUE';
      INPUT_LOAD='(-0.01,0.01)';
      OUTPUT_LOAD='(1.0,-1.0)';
    'B1':
      PIN_NUMBER='(B1)';
      BIDIRECTIONAL='TRUE';
      INPUT_LOAD='(-0.01,0.01)';
      OUTPUT_LOAD='(1.0,-1.0)';
    'C1':
      PIN_NUMBER='(C1)';
      BIDIRECTIONAL='TRUE';
      INPUT_LOAD='(-0.01,0.01)';
      OUTPUT_LOAD='(1.0,-1.0)';
    'D1':
      PIN_NUMBER='(D1)';
      BIDIRECTIONAL='TRUE';
      INPUT_LOAD='(-0.01,0.01)';
      OUTPUT_LOAD='(1.0,-1.0)';
    'P5_1':
      PIN_NUMBER='(P5_1)';
      PINUSE='POWER';
      NO_LOAD_CHECK='Both';
      NO_IO_CHECK='Both';
      NO_ASSERT_CHECK='TRUE';
      NO_DIR_CHECK='TRUE';
      ALLOW_CONNECT='TRUE';
    'P5_2':
      PIN_NUMBER='(P5_2)';
      PINUSE='POWER';
      NO_LOAD_CHECK='Both';
      NO_IO_CHECK='Both';
      NO_ASSERT_CHECK='TRUE';
      NO_DIR_CHECK='TRUE';
      ALLOW_CONNECT='TRUE';
    'P5_3':
      PIN_NUMBER='(P5_3)';
      PINUSE='POWER';
      NO_LOAD_CHECK='Both';
      NO_IO_CHECK='Both';
      NO_ASSERT_CHECK='TRUE';
      NO_DIR_CHECK='TRUE';
      ALLOW_CONNECT='TRUE';
    'P5_4':
      PIN_NUMBER='(P5_4)';
      PINUSE='POWER';
      NO_LOAD_CHECK='Both';
      NO_IO_CHECK='Both';
      NO_ASSERT_CHECK='TRUE';
      NO_DIR_CHECK='TRUE';
      ALLOW_CONNECT='TRUE';
    'P5_5':
      PIN_NUMBER='(P5_5)';
      PINUSE='POWER';
      NO_LOAD_CHECK='Both';
      NO_IO_CHECK='Both';
      NO_ASSERT_CHECK='TRUE';
      NO_DIR_CHECK='TRUE';
      ALLOW_CONNECT='TRUE';
    'P5_6':
      PIN_NUMBER='(P5_6)';
      PINUSE='POWER';
      NO_LOAD_CHECK='Both';
      NO_IO_CHECK='Both';
      NO_ASSERT_CHECK='TRUE';
      NO_DIR_CHECK='TRUE';
      ALLOW_CONNECT='TRUE';
    'P5_7':
      PIN_NUMBER='(P5_7)';
      PINUSE='POWER';
      NO_LOAD_CHECK='Both';
      NO_IO_CHECK='Both';
      NO_ASSERT_CHECK='TRUE';
      NO_DIR_CHECK='TRUE';
      ALLOW_CONNECT='TRUE';
    'P5_8':
      PIN_NUMBER='(P5_8)';
      PINUSE='POWER';
      NO_LOAD_CHECK='Both';
      NO_IO_CHECK='Both';
      NO_ASSERT_CHECK='TRUE';
      NO_DIR_CHECK='TRUE';
      ALLOW_CONNECT='TRUE';
    'P3_1':
      PIN_NUMBER='(P3_1)';
      PINUSE='POWER';
      NO_LOAD_CHECK='Both';
      NO_IO_CHECK='Both';
      NO_ASSERT_CHECK='TRUE';
      NO_DIR_CHECK='TRUE';
      ALLOW_CONNECT='TRUE';
    'P3_2':
      PIN_NUMBER='(P3_2)';
      PINUSE='POWER';
      NO_LOAD_CHECK='Both';
      NO_IO_CHECK='Both';
      NO_ASSERT_CHECK='TRUE';
      NO_DIR_CHECK='TRUE';
      ALLOW_CONNECT='TRUE';
    'P3_3':
      PIN_NUMBER='(P3_3)';
      PINUSE='POWER';
      NO_LOAD_CHECK='Both';
      NO_IO_CHECK='Both';
      NO_ASSERT_CHECK='TRUE';
      NO_DIR_CHECK='TRUE';
      ALLOW_CONNECT='TRUE';
    'P3_4':
      PIN_NUMBER='(P3_4)';
      PINUSE='POWER';
      NO_LOAD_CHECK='Both';
      NO_IO_CHECK='Both';
      NO_ASSERT_CHECK='TRUE';
      NO_DIR_CHECK='TRUE';
      ALLOW_CONNECT='TRUE';
    'P3_5':
      PIN_NUMBER='(P3_5)';
      PINUSE='POWER';
      NO_LOAD_CHECK='Both';
      NO_IO_CHECK='Both';
      NO_ASSERT_CHECK='TRUE';
      NO_DIR_CHECK='TRUE';
      ALLOW_CONNECT='TRUE';
    'P3_6':
      PIN_NUMBER='(P3_6)';
      PINUSE='POWER';
      NO_LOAD_CHECK='Both';
      NO_IO_CHECK='Both';
      NO_ASSERT_CHECK='TRUE';
      NO_DIR_CHECK='TRUE';
      ALLOW_CONNECT='TRUE';
    'P3_7':
      PIN_NUMBER='(P3_7)';
      PINUSE='POWER';
      NO_LOAD_CHECK='Both';
      NO_IO_CHECK='Both';
      NO_ASSERT_CHECK='TRUE';
      NO_DIR_CHECK='TRUE';
      ALLOW_CONNECT='TRUE';
    'P3_8':
      PIN_NUMBER='(P3_8)';
      PINUSE='POWER';
      NO_LOAD_CHECK='Both';
      NO_IO_CHECK='Both';
      NO_ASSERT_CHECK='TRUE';
      NO_DIR_CHECK='TRUE';
      ALLOW_CONNECT='TRUE';
    'P6_1':
      PIN_NUMBER='(P6_1)';
      PINUSE='POWER';
      NO_LOAD_CHECK='Both';
      NO_IO_CHECK='Both';
      NO_ASSERT_CHECK='TRUE';
      NO_DIR_CHECK='TRUE';
      ALLOW_CONNECT='TRUE';
    'P6_2':
      PIN_NUMBER='(P6_2)';
      PINUSE='POWER';
      NO_LOAD_CHECK='Both';
      NO_IO_CHECK='Both';
      NO_ASSERT_CHECK='TRUE';
      NO_DIR_CHECK='TRUE';
      ALLOW_CONNECT='TRUE';
    'P6_3':
      PIN_NUMBER='(P6_3)';
      PINUSE='POWER';
      NO_LOAD_CHECK='Both';
      NO_IO_CHECK='Both';
      NO_ASSERT_CHECK='TRUE';
      NO_DIR_CHECK='TRUE';
      ALLOW_CONNECT='TRUE';
    'P6_4':
      PIN_NUMBER='(P6_4)';
      PINUSE='POWER';
      NO_LOAD_CHECK='Both';
      NO_IO_CHECK='Both';
      NO_ASSERT_CHECK='TRUE';
      NO_DIR_CHECK='TRUE';
      ALLOW_CONNECT='TRUE';
    'P6_5':
      PIN_NUMBER='(P6_5)';
      PINUSE='POWER';
      NO_LOAD_CHECK='Both';
      NO_IO_CHECK='Both';
      NO_ASSERT_CHECK='TRUE';
      NO_DIR_CHECK='TRUE';
      ALLOW_CONNECT='TRUE';
    'P6_6':
      PIN_NUMBER='(P6_6)';
      PINUSE='POWER';
      NO_LOAD_CHECK='Both';
      NO_IO_CHECK='Both';
      NO_ASSERT_CHECK='TRUE';
      NO_DIR_CHECK='TRUE';
      ALLOW_CONNECT='TRUE';
    'P6_7':
      PIN_NUMBER='(P6_7)';
      PINUSE='POWER';
      NO_LOAD_CHECK='Both';
      NO_IO_CHECK='Both';
      NO_ASSERT_CHECK='TRUE';
      NO_DIR_CHECK='TRUE';
      ALLOW_CONNECT='TRUE';
    'P6_8':
      PIN_NUMBER='(P6_8)';
      PINUSE='POWER';
      NO_LOAD_CHECK='Both';
      NO_IO_CHECK='Both';
      NO_ASSERT_CHECK='TRUE';
      NO_DIR_CHECK='TRUE';
      ALLOW_CONNECT='TRUE';
    'A3':
      PIN_NUMBER='(A3)';
      BIDIRECTIONAL='TRUE';
      INPUT_LOAD='(-0.01,0.01)';
      OUTPUT_LOAD='(1.0,-1.0)';
    'B3':
      PIN_NUMBER='(B3)';
      BIDIRECTIONAL='TRUE';
      INPUT_LOAD='(-0.01,0.01)';
      OUTPUT_LOAD='(1.0,-1.0)';
    'C3':
      PIN_NUMBER='(C3)';
      BIDIRECTIONAL='TRUE';
      INPUT_LOAD='(-0.01,0.01)';
      OUTPUT_LOAD='(1.0,-1.0)';
    'D3':
      PIN_NUMBER='(D3)';
      BIDIRECTIONAL='TRUE';
      INPUT_LOAD='(-0.01,0.01)';
      OUTPUT_LOAD='(1.0,-1.0)';
  end_pin;
  body
    PART_NAME='CONN60_101062636003K02LF';
    BODY_NAME='CONN60_101062636003K02LF';
    PHYS_DES_PREFIX='J';
    CLASS='IO';
    NC_PINS='(SCR_H1,SCR_H2)';
  end_body;
end_primitive;

END.
